(kicad_pcb
	(version 20260206)
	(generator "pcbnew")
	(generator_version "10.0")
	(general
		(thickness 1.6)
		(legacy_teardrops no)
	)
	(paper "A4")
	(title_block
		(title "Bryce Canyon_IOM_IOC_16318-2_OCP.brd")
		(comment 1 "Bryce Canyon / footprints 1201-1208 of 1605")
	)
	(layers
		(0 "F.Cu" signal "TOP")
		(4 "In1.Cu" signal "L2GND")
		(6 "In2.Cu" signal "L3")
		(8 "In3.Cu" signal "L4VCC")
		(10 "In4.Cu" signal "L5VCC")
		(12 "In5.Cu" signal "L6")
		(14 "In6.Cu" signal "L7GND")
		(2 "B.Cu" signal "BOTTOM")
		(9 "F.Adhes" user "F.Adhesive")
		(11 "B.Adhes" user "B.Adhesive")
		(13 "F.Paste" user "Package Geometry/Pastemask Top")
		(15 "B.Paste" user "Package Geometry/Pastemask Bottom")
		(5 "F.SilkS" user "Ref Des/Silkscreen Top")
		(7 "B.SilkS" user "Ref Des/Silkscreen Bottom")
		(1 "F.Mask" user "Board Geometry/Soldermask Top")
		(3 "B.Mask" user "Board Geometry/Soldermask Bottom")
		(17 "Dwgs.User" user "User.Drawings")
		(19 "Cmts.User" user "User.Comments")
		(21 "Eco1.User" user "User.Eco1")
		(23 "Eco2.User" user "User.Eco2")
		(25 "Edge.Cuts" user "Board Geometry/Outline")
		(27 "Margin" user)
		(31 "F.CrtYd" user "Package Geometry/Place Bound Top")
		(29 "B.CrtYd" user "Package Geometry/Place Bound Bottom")
		(35 "F.Fab" user "Ref Des/Assembly Top")
		(33 "B.Fab" user "Ref Des/Assembly Bottom")
	)
	(footprint ""
		(layer "B.Cu")
		(at 91.8972 -152.8318 180)
		(property "Reference" "C10"
			(at 0 0 0)
			(layer "B.SilkS")
			(hide yes)
			(effects
				(font
					(size 1.27 1.27)
				)
				(justify mirror)
			)
		)
		(property "Value" "SC1U16V2KX-7-GP"
			(at -1.7526 -1.6002 180)
			(unlocked yes)
			(layer "B.Fab")
			(hide yes)
			(effects
				(font
					(size 1.016 1.016)
					(thickness 0.1524)
				)
				(justify mirror)
			)
		)
		(property "Device Type" "C402-TO0D2H24"
			(at -1.7526 -3.1242 180)
			(unlocked yes)
			(layer "B.Fab")
			(hide yes)
			(effects
				(font
					(size 1.016 1.016)
					(thickness 0.1524)
				)
				(justify mirror)
			)
		)
		(duplicate_pad_numbers_are_jumpers no)
		(fp_rect
			(start 0.4826 0.889)
			(end -0.4826 -0.889)
			(stroke
				(width 0)
				(type default)
			)
			(fill no)
			(layer "B.CrtYd")
		)
		(fp_rect
			(start 0.4826 0.889)
			(end -0.4826 -0.889)
			(stroke
				(width 0)
				(type default)
			)
			(fill no)
			(layer "B.Fab")
		)
		(pad "1" smd custom
			(at 0 -0.4572)
			(size 0.1524 0.1524)
			(layers "B.Cu" "B.Mask" "B.Paste")
			(net "P3V3_STBY")
			(options
				(clearance outline)
				(anchor circle)
			)
			(primitives
				(gr_poly
					(pts
						(arc
							(start -0.254 -0.3048)
							(mid -0.325842 -0.275042)
							(end -0.3556 -0.2032)
						)
						(arc
							(start -0.3556 0.2032)
							(mid -0.325842 0.275042)
							(end -0.254 0.3048)
						)
						(arc
							(start 0.254 0.3048)
							(mid 0.325842 0.275042)
							(end 0.3556 0.2032)
						)
						(arc
							(start 0.3556 -0.2032)
							(mid 0.325842 -0.275042)
							(end 0.254 -0.3048)
						)
					)
					(width 0)
					(fill yes)
				)
			)
		)
		(pad "2" smd custom
			(at 0 0.4572)
			(size 0.1524 0.1524)
			(layers "B.Cu" "B.Mask" "B.Paste")
			(net "GND")
			(options
				(clearance outline)
				(anchor circle)
			)
			(primitives
				(gr_poly
					(pts
						(arc
							(start -0.254 -0.3048)
							(mid -0.325842 -0.275042)
							(end -0.3556 -0.2032)
						)
						(arc
							(start -0.3556 0.2032)
							(mid -0.325842 0.275042)
							(end -0.254 0.3048)
						)
						(arc
							(start 0.254 0.3048)
							(mid 0.325842 0.275042)
							(end 0.3556 0.2032)
						)
						(arc
							(start 0.3556 -0.2032)
							(mid 0.325842 -0.275042)
							(end 0.254 -0.3048)
						)
					)
					(width 0)
					(fill yes)
				)
			)
		)
	)
	(footprint ""
		(layer "B.Cu")
		(at 95.377 -179.324)
		(property "Reference" "R101"
			(at 0 0 0)
			(layer "B.SilkS")
			(hide yes)
			(effects
				(font
					(size 1.27 1.27)
				)
				(justify mirror)
			)
		)
		(property "Value" "0R2J-2-GP"
			(at -0.064008 -3.993896 0)
			(unlocked yes)
			(layer "B.Fab")
			(hide yes)
			(effects
				(font
					(size 1.016 1.016)
					(thickness 0.1524)
				)
				(justify mirror)
			)
		)
		(property "Device Type" "R402H16"
			(at -0.064008 -5.517896 0)
			(unlocked yes)
			(layer "B.Fab")
			(hide yes)
			(effects
				(font
					(size 1.016 1.016)
					(thickness 0.1524)
				)
				(justify mirror)
			)
		)
		(duplicate_pad_numbers_are_jumpers no)
		(fp_line
			(start -0.508 -0.9398)
			(end 0.508 -0.9398)
			(stroke
				(width 0.1524)
				(type default)
			)
			(layer "B.SilkS")
		)
		(fp_line
			(start 0.508 -0.9398)
			(end 0.508 0.9398)
			(stroke
				(width 0.1524)
				(type default)
			)
			(layer "B.SilkS")
		)
		(fp_rect
			(start 0.508 0.9398)
			(end -0.508 -0.9398)
			(stroke
				(width 0)
				(type default)
			)
			(fill no)
			(layer "B.CrtYd")
		)
		(fp_rect
			(start 0.508 0.9398)
			(end -0.508 -0.9398)
			(stroke
				(width 0)
				(type default)
			)
			(fill no)
			(layer "B.Fab")
		)
		(pad "1" smd custom
			(at 0 -0.4445 180)
			(size 0.1397 0.1397)
			(layers "B.Cu" "B.Mask" "B.Paste")
			(net "I2C_COMP_ALERT_N")
			(options
				(clearance outline)
				(anchor circle)
			)
			(primitives
				(gr_poly
					(pts
						(arc
							(start -0.1778 0.2794)
							(mid -0.249642 0.249642)
							(end -0.2794 0.1778)
						)
						(arc
							(start -0.2794 -0.1778)
							(mid -0.249642 -0.249642)
							(end -0.1778 -0.2794)
						)
						(arc
							(start 0.1778 -0.2794)
							(mid 0.249642 -0.249642)
							(end 0.2794 -0.1778)
						)
						(arc
							(start 0.2794 0.1778)
							(mid 0.249642 0.249642)
							(end 0.1778 0.2794)
						)
					)
					(width 0)
					(fill yes)
				)
			)
		)
		(pad "2" smd custom
			(at 0 0.4445 180)
			(size 0.1397 0.1397)
			(layers "B.Cu" "B.Mask" "B.Paste")
			(net "I2C_BMC_COMP_ALERT_N_R")
			(options
				(clearance outline)
				(anchor circle)
			)
			(primitives
				(gr_poly
					(pts
						(arc
							(start -0.1778 0.2794)
							(mid -0.249642 0.249642)
							(end -0.2794 0.1778)
						)
						(arc
							(start -0.2794 -0.1778)
							(mid -0.249642 -0.249642)
							(end -0.1778 -0.2794)
						)
						(arc
							(start 0.1778 -0.2794)
							(mid 0.249642 -0.249642)
							(end 0.2794 -0.1778)
						)
						(arc
							(start 0.2794 0.1778)
							(mid 0.249642 0.249642)
							(end 0.1778 0.2794)
						)
					)
					(width 0)
					(fill yes)
				)
			)
		)
	)
	(footprint ""
		(layer "B.Cu")
		(at 175.41748 -81.51876 180)
		(property "Reference" "C363"
			(at 0 0 0)
			(layer "B.SilkS")
			(hide yes)
			(effects
				(font
					(size 1.27 1.27)
				)
				(justify mirror)
			)
		)
		(property "Value" "SC22U6D3V3MX-9-GP-U"
			(at 0 -2.8194 180)
			(unlocked yes)
			(layer "B.Fab")
			(hide yes)
			(effects
				(font
					(size 1.016 1.016)
					(thickness 0.1524)
				)
				(justify mirror)
			)
		)
		(property "Device Type" "C603H40"
			(at 0 -4.3434 180)
			(unlocked yes)
			(layer "B.Fab")
			(hide yes)
			(effects
				(font
					(size 1.016 1.016)
					(thickness 0.1524)
				)
				(justify mirror)
			)
		)
		(duplicate_pad_numbers_are_jumpers no)
		(fp_line
			(start -0.508 0)
			(end 0.508 0)
			(stroke
				(width 0.2032)
				(type default)
			)
			(layer "B.SilkS")
		)
		(fp_rect
			(start 0.5842 1.3335)
			(end -0.5842 -1.3335)
			(stroke
				(width 0)
				(type default)
			)
			(fill no)
			(layer "B.CrtYd")
		)
		(fp_rect
			(start 0.5842 1.3335)
			(end -0.5842 -1.3335)
			(stroke
				(width 0)
				(type default)
			)
			(fill no)
			(layer "B.Fab")
		)
		(pad "1" smd custom
			(at 0 -0.762)
			(size 0.2159 0.2159)
			(layers "B.Cu" "B.Mask" "B.Paste")
			(net "PCE_AVDD")
			(options
				(clearance outline)
				(anchor circle)
			)
			(primitives
				(gr_poly
					(pts
						(arc
							(start -0.3302 0.4318)
							(mid -0.402042 0.402042)
							(end -0.4318 0.3302)
						)
						(arc
							(start -0.4318 -0.3302)
							(mid -0.402042 -0.402042)
							(end -0.3302 -0.4318)
						)
						(arc
							(start 0.3302 -0.4318)
							(mid 0.402042 -0.402042)
							(end 0.4318 -0.3302)
						)
						(arc
							(start 0.4318 0.3302)
							(mid 0.402042 0.402042)
							(end 0.3302 0.4318)
						)
					)
					(width 0)
					(fill yes)
				)
			)
		)
		(pad "2" smd custom
			(at 0 0.762)
			(size 0.2159 0.2159)
			(layers "B.Cu" "B.Mask" "B.Paste")
			(net "GND")
			(options
				(clearance outline)
				(anchor circle)
			)
			(primitives
				(gr_poly
					(pts
						(arc
							(start -0.3302 0.4318)
							(mid -0.402042 0.402042)
							(end -0.4318 0.3302)
						)
						(arc
							(start -0.4318 -0.3302)
							(mid -0.402042 -0.402042)
							(end -0.3302 -0.4318)
						)
						(arc
							(start 0.3302 -0.4318)
							(mid 0.402042 -0.402042)
							(end 0.4318 -0.3302)
						)
						(arc
							(start 0.4318 0.3302)
							(mid 0.402042 0.402042)
							(end 0.3302 0.4318)
						)
					)
					(width 0)
					(fill yes)
				)
			)
		)
	)
	(footprint ""
		(layer "B.Cu")
		(at 181.302406 -72.17029)
		(property "Reference" "TP118"
			(at 0 0 0)
			(layer "B.SilkS")
			(hide yes)
			(effects
				(font
					(size 1.27 1.27)
				)
				(justify mirror)
			)
		)
		(property "Value" "TPAD28-2-GP"
			(at 0.0127 -1.6637 0)
			(unlocked yes)
			(layer "B.Fab")
			(hide yes)
			(effects
				(font
					(size 1.016 1.016)
					(thickness 0.1524)
				)
				(justify mirror)
			)
		)
		(property "Device Type" "TPAD28"
			(at 0.0127 -3.1877 0)
			(unlocked yes)
			(layer "B.Fab")
			(hide yes)
			(effects
				(font
					(size 1.016 1.016)
					(thickness 0.1524)
				)
				(justify mirror)
			)
		)
		(duplicate_pad_numbers_are_jumpers no)
		(fp_poly
			(pts
				(arc
					(start 0.3556 0)
					(mid -0.3556 0)
					(end 0.3556 0)
				)
			)
			(stroke
				(width 0)
				(type default)
			)
			(fill no)
			(layer "B.CrtYd")
		)
		(fp_poly
			(pts
				(arc
					(start 0.6096 0)
					(mid -0.6096 0)
					(end 0.6096 0)
				)
			)
			(stroke
				(width 0)
				(type default)
			)
			(fill no)
			(layer "B.Fab")
		)
		(pad "1" smd circle
			(at 0 0 180)
			(size 0.7112 0.7112)
			(layers "B.Cu" "B.Mask" "B.Paste")
			(net "IOC_GPIO_29")
		)
	)
	(footprint ""
		(layer "B.Cu")
		(at 95.863664 -157.607762 -90)
		(property "Reference" "R22"
			(at 0 0 90)
			(layer "B.SilkS")
			(hide yes)
			(effects
				(font
					(size 1.27 1.27)
				)
				(justify mirror)
			)
		)
		(property "Value" "4K7R2F-GP"
			(at -0.064008 -3.993896 270)
			(unlocked yes)
			(layer "B.Fab")
			(hide yes)
			(effects
				(font
					(size 1.016 1.016)
					(thickness 0.1524)
				)
				(justify mirror)
			)
		)
		(property "Device Type" "R402H16"
			(at -0.064008 -5.517896 270)
			(unlocked yes)
			(layer "B.Fab")
			(hide yes)
			(effects
				(font
					(size 1.016 1.016)
					(thickness 0.1524)
				)
				(justify mirror)
			)
		)
		(duplicate_pad_numbers_are_jumpers no)
		(fp_line
			(start -0.508 -0.9398)
			(end 0.508 -0.9398)
			(stroke
				(width 0.1524)
				(type default)
			)
			(layer "B.SilkS")
		)
		(fp_line
			(start 0.508 -0.9398)
			(end 0.508 0.9398)
			(stroke
				(width 0.1524)
				(type default)
			)
			(layer "B.SilkS")
		)
		(fp_rect
			(start 0.508 0.9398)
			(end -0.508 -0.9398)
			(stroke
				(width 0)
				(type default)
			)
			(fill no)
			(layer "B.CrtYd")
		)
		(fp_rect
			(start 0.508 0.9398)
			(end -0.508 -0.9398)
			(stroke
				(width 0)
				(type default)
			)
			(fill no)
			(layer "B.Fab")
		)
		(pad "1" smd custom
			(at 0 -0.4445 90)
			(size 0.1397 0.1397)
			(layers "B.Cu" "B.Mask" "B.Paste")
			(net "CFG_SEL1")
			(options
				(clearance outline)
				(anchor circle)
			)
			(primitives
				(gr_poly
					(pts
						(arc
							(start -0.1778 0.2794)
							(mid -0.249642 0.249642)
							(end -0.2794 0.1778)
						)
						(arc
							(start -0.2794 -0.1778)
							(mid -0.249642 -0.249642)
							(end -0.1778 -0.2794)
						)
						(arc
							(start 0.1778 -0.2794)
							(mid 0.249642 -0.249642)
							(end 0.2794 -0.1778)
						)
						(arc
							(start 0.2794 0.1778)
							(mid 0.249642 0.249642)
							(end 0.1778 0.2794)
						)
					)
					(width 0)
					(fill yes)
				)
			)
		)
		(pad "2" smd custom
			(at 0 0.4445 90)
			(size 0.1397 0.1397)
			(layers "B.Cu" "B.Mask" "B.Paste")
			(net "GND")
			(options
				(clearance outline)
				(anchor circle)
			)
			(primitives
				(gr_poly
					(pts
						(arc
							(start -0.1778 0.2794)
							(mid -0.249642 0.249642)
							(end -0.2794 0.1778)
						)
						(arc
							(start -0.2794 -0.1778)
							(mid -0.249642 -0.249642)
							(end -0.1778 -0.2794)
						)
						(arc
							(start 0.1778 -0.2794)
							(mid 0.249642 -0.249642)
							(end 0.2794 -0.1778)
						)
						(arc
							(start 0.2794 0.1778)
							(mid 0.249642 0.249642)
							(end 0.1778 0.2794)
						)
					)
					(width 0)
					(fill yes)
				)
			)
		)
	)
	(footprint ""
		(layer "B.Cu")
		(at 61.4426 -136.906 90)
		(property "Reference" "R739"
			(at 0 0 90)
			(layer "B.SilkS")
			(hide yes)
			(effects
				(font
					(size 1.27 1.27)
				)
				(justify mirror)
			)
		)
		(property "Value" "10KR2F-2-GP"
			(at -0.064008 -3.993896 90)
			(unlocked yes)
			(layer "B.Fab")
			(hide yes)
			(effects
				(font
					(size 1.016 1.016)
					(thickness 0.1524)
				)
				(justify mirror)
			)
		)
		(property "Device Type" "R402H16"
			(at -0.064008 -5.517896 90)
			(unlocked yes)
			(layer "B.Fab")
			(hide yes)
			(effects
				(font
					(size 1.016 1.016)
					(thickness 0.1524)
				)
				(justify mirror)
			)
		)
		(duplicate_pad_numbers_are_jumpers no)
		(fp_line
			(start 0.508 -0.9398)
			(end 0.508 0.9398)
			(stroke
				(width 0.1524)
				(type default)
			)
			(layer "B.SilkS")
		)
		(fp_line
			(start -0.508 -0.9398)
			(end 0.508 -0.9398)
			(stroke
				(width 0.1524)
				(type default)
			)
			(layer "B.SilkS")
		)
		(fp_rect
			(start 0.508 0.9398)
			(end -0.508 -0.9398)
			(stroke
				(width 0)
				(type default)
			)
			(fill no)
			(layer "B.CrtYd")
		)
		(fp_rect
			(start 0.508 0.9398)
			(end -0.508 -0.9398)
			(stroke
				(width 0)
				(type default)
			)
			(fill no)
			(layer "B.Fab")
		)
		(pad "1" smd custom
			(at 0 -0.4445 270)
			(size 0.1397 0.1397)
			(layers "B.Cu" "B.Mask" "B.Paste")
			(net "TP_BMC_GPIOA0")
			(options
				(clearance outline)
				(anchor circle)
			)
			(primitives
				(gr_poly
					(pts
						(arc
							(start -0.1778 0.2794)
							(mid -0.249642 0.249642)
							(end -0.2794 0.1778)
						)
						(arc
							(start -0.2794 -0.1778)
							(mid -0.249642 -0.249642)
							(end -0.1778 -0.2794)
						)
						(arc
							(start 0.1778 -0.2794)
							(mid 0.249642 -0.249642)
							(end 0.2794 -0.1778)
						)
						(arc
							(start 0.2794 0.1778)
							(mid 0.249642 0.249642)
							(end 0.1778 0.2794)
						)
					)
					(width 0)
					(fill yes)
				)
			)
		)
		(pad "2" smd custom
			(at 0 0.4445 270)
			(size 0.1397 0.1397)
			(layers "B.Cu" "B.Mask" "B.Paste")
			(net "GND")
			(options
				(clearance outline)
				(anchor circle)
			)
			(primitives
				(gr_poly
					(pts
						(arc
							(start -0.1778 0.2794)
							(mid -0.249642 0.249642)
							(end -0.2794 0.1778)
						)
						(arc
							(start -0.2794 -0.1778)
							(mid -0.249642 -0.249642)
							(end -0.1778 -0.2794)
						)
						(arc
							(start 0.1778 -0.2794)
							(mid 0.249642 -0.249642)
							(end 0.2794 -0.1778)
						)
						(arc
							(start 0.2794 0.1778)
							(mid 0.249642 0.249642)
							(end 0.1778 0.2794)
						)
					)
					(width 0)
					(fill yes)
				)
			)
		)
	)
	(footprint ""
		(layer "B.Cu")
		(at 92.9894 -132.0546 -90)
		(property "Reference" "U100"
			(at 0 0 90)
			(layer "B.SilkS")
			(hide yes)
			(effects
				(font
					(size 1.27 1.27)
				)
				(justify mirror)
			)
		)
		(property "Value" "SNLVC1G126DCKR-GP"
			(at 2.3368 -8.6868 270)
			(unlocked yes)
			(layer "B.Fab")
			(hide yes)
			(effects
				(font
					(size 1.016 1.016)
					(thickness 0.1524)
				)
				(justify mirror)
			)
		)
		(property "Device Type" "SC70-5H44"
			(at 2.3114 -10.414 270)
			(unlocked yes)
			(layer "B.Fab")
			(hide yes)
			(effects
				(font
					(size 1.016 1.016)
					(thickness 0.1524)
				)
				(justify mirror)
			)
		)
		(duplicate_pad_numbers_are_jumpers no)
		(fp_line
			(start -1.27 1.7018)
			(end 1.27 1.7018)
			(stroke
				(width 0.1524)
				(type default)
			)
			(layer "B.SilkS")
		)
		(fp_line
			(start 1.27 1.7018)
			(end 1.27 -1.7018)
			(stroke
				(width 0.1524)
				(type default)
			)
			(layer "B.SilkS")
		)
		(fp_line
			(start -1.27 -1.7018)
			(end -1.27 1.7018)
			(stroke
				(width 0.1524)
				(type default)
			)
			(layer "B.SilkS")
		)
		(fp_line
			(start 1.27 -1.7018)
			(end -1.27 -1.7018)
			(stroke
				(width 0.1524)
				(type default)
			)
			(layer "B.SilkS")
		)
		(fp_line
			(start -1.3843 -1.8034)
			(end -1.3843 -1.1176)
			(stroke
				(width 0.3302)
				(type default)
			)
			(layer "B.SilkS")
		)
		(fp_line
			(start -0.6604 -1.8034)
			(end -1.3843 -1.8034)
			(stroke
				(width 0.3302)
				(type default)
			)
			(layer "B.SilkS")
		)
		(fp_rect
			(start 1.524 1.9558)
			(end -1.524 -1.9558)
			(stroke
				(width 0)
				(type default)
			)
			(fill no)
			(layer "B.CrtYd")
		)
		(fp_poly
			(pts
				(xy 1.524 -1.9558) (xy -1.524 -1.9558) (xy -1.524 1.9558) (xy 1.524 1.9558)
			)
			(stroke
				(width 0)
				(type default)
			)
			(fill no)
			(layer "B.Fab")
		)
		(pad "1" smd rect
			(at -0.65024 -0.8255 90)
			(size 0.4064 1.2192)
			(layers "B.Cu" "B.Mask" "B.Paste")
			(net "DEBUG_CARD_PRSNT")
		)
		(pad "2" smd rect
			(at 0 -0.8255 90)
			(size 0.4064 1.2192)
			(layers "B.Cu" "B.Mask" "B.Paste")
			(net "DEBUG_UART_IOM_TX")
		)
		(pad "3" smd rect
			(at 0.65024 -0.8255 90)
			(size 0.4064 1.2192)
			(layers "B.Cu" "B.Mask" "B.Paste")
			(net "GND")
		)
		(pad "4" smd rect
			(at 0.65024 0.8255 90)
			(size 0.4064 1.2192)
			(layers "B.Cu" "B.Mask" "B.Paste")
			(net "UART_IOM_TX")
		)
		(pad "5" smd rect
			(at -0.65024 0.8255 90)
			(size 0.4064 1.2192)
			(layers "B.Cu" "B.Mask" "B.Paste")
			(net "P3V3_STBY")
		)
	)
	(footprint ""
		(layer "B.Cu")
		(at 59.563 -162.0266 -90)
		(property "Reference" "R406"
			(at 0 0 90)
			(layer "B.SilkS")
			(hide yes)
			(effects
				(font
					(size 1.27 1.27)
				)
				(justify mirror)
			)
		)
		(property "Value" "1KR2F-3-GP"
			(at -0.064008 -3.993896 270)
			(unlocked yes)
			(layer "B.Fab")
			(hide yes)
			(effects
				(font
					(size 1.016 1.016)
					(thickness 0.1524)
				)
				(justify mirror)
			)
		)
		(property "Device Type" "R402H16"
			(at -0.064008 -5.517896 270)
			(unlocked yes)
			(layer "B.Fab")
			(hide yes)
			(effects
				(font
					(size 1.016 1.016)
					(thickness 0.1524)
				)
				(justify mirror)
			)
		)
		(duplicate_pad_numbers_are_jumpers no)
		(fp_line
			(start -0.508 -0.9398)
			(end 0.508 -0.9398)
			(stroke
				(width 0.1524)
				(type default)
			)
			(layer "B.SilkS")
		)
		(fp_line
			(start 0.508 -0.9398)
			(end 0.508 0.9398)
			(stroke
				(width 0.1524)
				(type default)
			)
			(layer "B.SilkS")
		)
		(fp_rect
			(start 0.508 0.9398)
			(end -0.508 -0.9398)
			(stroke
				(width 0)
				(type default)
			)
			(fill no)
			(layer "B.CrtYd")
		)
		(fp_rect
			(start 0.508 0.9398)
			(end -0.508 -0.9398)
			(stroke
				(width 0)
				(type default)
			)
			(fill no)
			(layer "B.Fab")
		)
		(pad "1" smd custom
			(at 0 -0.4445 90)
			(size 0.1397 0.1397)
			(layers "B.Cu" "B.Mask" "B.Paste")
			(net "ADC_P1V8")
			(options
				(clearance outline)
				(anchor circle)
			)
			(primitives
				(gr_poly
					(pts
						(arc
							(start -0.1778 0.2794)
							(mid -0.249642 0.249642)
							(end -0.2794 0.1778)
						)
						(arc
							(start -0.2794 -0.1778)
							(mid -0.249642 -0.249642)
							(end -0.1778 -0.2794)
						)
						(arc
							(start 0.1778 -0.2794)
							(mid 0.249642 -0.249642)
							(end 0.2794 -0.1778)
						)
						(arc
							(start 0.2794 0.1778)
							(mid 0.249642 0.249642)
							(end 0.1778 0.2794)
						)
					)
					(width 0)
					(fill yes)
				)
			)
		)
		(pad "2" smd custom
			(at 0 0.4445 90)
			(size 0.1397 0.1397)
			(layers "B.Cu" "B.Mask" "B.Paste")
			(net "GND")
			(options
				(clearance outline)
				(anchor circle)
			)
			(primitives
				(gr_poly
					(pts
						(arc
							(start -0.1778 0.2794)
							(mid -0.249642 0.249642)
							(end -0.2794 0.1778)
						)
						(arc
							(start -0.2794 -0.1778)
							(mid -0.249642 -0.249642)
							(end -0.1778 -0.2794)
						)
						(arc
							(start 0.1778 -0.2794)
							(mid 0.249642 -0.249642)
							(end 0.2794 -0.1778)
						)
						(arc
							(start 0.2794 0.1778)
							(mid 0.249642 0.249642)
							(end 0.1778 0.2794)
						)
					)
					(width 0)
					(fill yes)
				)
			)
		)
	)
)
